# BASEBOARD_FAB2 (Tioga Pass) — schematic netlist excerpt (pin names and nets, part order shuffled) for the footprints in the layout excerpt that follows; sources: Cadence DE-HDL packaged netlist, KiCad conversion of Wiwynn_Tioga_Pass_MB.brd

J9L2  SCONN288_H44441003  SCONN  pkg PIP  page 86
  \12v\(1)  = P12V_NVDIMM_KLM
  VSS(93)  = GND
  DQ(4)  = M_L_DQ<4>
  VSS(92)  = GND
  DQ(0)  = M_L_DQ<0>
  VSS(91)  = GND
  DQS9P  = M_L_DQS_DP<9>
  DQS9N  = M_L_DQS_DN<9>
  VSS(90)  = GND
  DQ(6)  = M_L_DQ<6>
  VSS(89)  = GND
  DQ(2)  = M_L_DQ<2>
  VSS(88)  = GND
  DQ(12)  = M_L_DQ<12>
  VSS(87)  = GND
  DQ(8)  = M_L_DQ<8>
  VSS(86)  = GND
  DQS10P  = M_L_DQS_DP<10>
  DQS10N  = M_L_DQS_DN<10>
  VSS(85)  = GND
  DQ(14)  = M_L_DQ<14>
  VSS(84)  = GND
  DQ(10)  = M_L_DQ<10>
  VSS(83)  = GND
  DQ(20)  = M_L_DQ<20>
  VSS(82)  = GND
  DQ(16)  = M_L_DQ<16>
  VSS(81)  = GND
  DQS11P  = M_L_DQS_DP<11>
  DQS11N  = M_L_DQS_DN<11>
  VSS(80)  = GND
  DQ(22)  = M_L_DQ<22>
  VSS(79)  = GND
  DQ(18)  = M_L_DQ<18>
  VSS(78)  = GND
  DQ(28)  = M_L_DQ<28>
  VSS(77)  = GND
  DQ(24)  = M_L_DQ<24>
  VSS(76)  = GND
  DQS12P  = M_L_DQS_DP<12>
  DQS12N  = M_L_DQS_DN<12>
  VSS(75)  = GND
  DQ(30)  = M_L_DQ<30>
  VSS(74)  = GND
  DQ(26)  = M_L_DQ<26>
  VSS(73)  = GND
  CB(4)  = M_L_ECC<4>
  VSS(72)  = GND
  CB(0)  = M_L_ECC<0>
  VSS(71)  = GND
  DQS17P  = M_L_DQS_DP<17>
  DQS17N  = M_L_DQS_DN<17>
  VSS(70)  = GND
  CB(6)  = M_L_ECC<6>
  VSS(69)  = GND
  CB(2)  = M_L_ECC<2>
  VSS(68)  = GND
  RESET_N  = M_KLM_RST_N
  VDD(25)  = PVDDQ_KLM
  CKE(0)  = M_L_CKE<2>
  VDD(24)  = PVDDQ_KLM
  ACT_N  = M_L_ACT_N
  BG(0)  = M_L_BG<0>
  VDD(23)  = PVDDQ_KLM
  A12  = M_L_MA<12>
  A9  = M_L_MA<9>
  VDD(22)  = PVDDQ_KLM
  A8  = M_L_MA<8>
  A6  = M_L_MA<6>
  VDD(21)  = PVDDQ_KLM
  A3  = M_L_MA<3>
  A1  = M_L_MA<1>
  VDD(20)  = PVDDQ_KLM
  CK0P  = M_L_CLK_DP<2>
  CK0N  = M_L_CLK_DN<2>
  VDD(19)  = PVDDQ_KLM
  VTT(1)  = PVTT_KLM
  EVENT_N  = FM_DIMM_EVENT_COD_N
  A0  = M_L_MA<0>
  VDD(18)  = PVDDQ_KLM
  BA(0)  = M_L_BA<0>
  A16_RAS_N  = M_L_MA<16>
  VDD(17)  = PVDDQ_KLM
  S0_N  = M_L_CS_N<4>
  VDD(16)  = PVDDQ_KLM
  A15_CAS_N  = M_L_MA<15>
  ODT(0)  = M_L_ODT<2>
  VDD(15)  = PVDDQ_KLM
  S1_N  = M_L_CS_N<5>
  VDD(14)  = PVDDQ_KLM
  ODT(1)  = M_L_ODT<3>
  VDD(13)  = PVDDQ_KLM
  S2_N_C(0)  = M_L_CS_N<6>
  VSS(67)  = GND
  DQ(36)  = M_L_DQ<36>
  VSS(66)  = GND
  DQ(32)  = M_L_DQ<32>
  VSS(65)  = GND
  DQS13P  = M_L_DQS_DP<13>
  DQS13N  = M_L_DQS_DN<13>
  VSS(64)  = GND
  DQ(38)  = M_L_DQ<38>
  VSS(63)  = GND
  DQ(34)  = M_L_DQ<34>
  VSS(62)  = GND
  DQ(44)  = M_L_DQ<44>
  VSS(61)  = GND
  DQ(40)  = M_L_DQ<40>
  VSS(60)  = GND
  DQS14P  = M_L_DQS_DP<14>
  DQS14N  = M_L_DQS_DN<14>
  VSS(59)  = GND
  DQ(46)  = M_L_DQ<46>
  VSS(58)  = GND
  DQ(42)  = M_L_DQ<42>
  VSS(57)  = GND
  DQ(52)  = M_L_DQ<52>
  VSS(56)  = GND
  DQ(48)  = M_L_DQ<48>
  VSS(55)  = GND
  DQS15P  = M_L_DQS_DP<15>
  DQS15N  = M_L_DQS_DN<15>
  VSS(54)  = GND
  DQ(54)  = M_L_DQ<54>
  VSS(53)  = GND
  DQ(50)  = M_L_DQ<50>
  VSS(52)  = GND
  DQ(60)  = M_L_DQ<60>
  VSS(51)  = GND
  DQ(56)  = M_L_DQ<56>
  VSS(50)  = GND
  DQS16P  = M_L_DQS_DP<16>
  DQS16N  = M_L_DQS_DN<16>
  VSS(49)  = GND
  DQ(62)  = M_L_DQ<62>
  VSS(48)  = GND
  DQ(58)  = M_L_DQ<58>
  VSS(47)  = GND
  SA(0)  = PVPP_KLM
  SA(1)  = PVPP_KLM
  SCL  = SMB_DDR_KLM_VPP_SCL
  VPP(4)  = PVPP_KLM
  VPP(3)  = PVPP_KLM
  RFU(2)  = TP_CH_L_DIMM0_RFU_2
  \12v\(0)  = P12V_NVDIMM_KLM
  VREFCA  = M_L_VREF
  VSS(46)  = GND
  DQ(5)  = M_L_DQ<5>
  VSS(45)  = GND
  DQ(1)  = M_L_DQ<1>
  VSS(44)  = GND
  DQS0N  = M_L_DQS_DN<0>
  DQS0P  = M_L_DQS_DP<0>
  VSS(43)  = GND
  DQ(7)  = M_L_DQ<7>
  VSS(42)  = GND
  DQ(3)  = M_L_DQ<3>
  VSS(41)  = GND
  DQ(13)  = M_L_DQ<13>
  VSS(40)  = GND
  DQ(9)  = M_L_DQ<9>
  VSS(39)  = GND
  DQS1N  = M_L_DQS_DN<1>
  DQS1P  = M_L_DQS_DP<1>
  VSS(38)  = GND
  DQ(15)  = M_L_DQ<15>
  VSS(37)  = GND
  DQ(11)  = M_L_DQ<11>
  VSS(36)  = GND
  DQ(21)  = M_L_DQ<21>
  VSS(35)  = GND
  DQ(17)  = M_L_DQ<17>
  VSS(34)  = GND
  DQS2N  = M_L_DQS_DN<2>
  DQS2P  = M_L_DQS_DP<2>
  VSS(33)  = GND
  DQ(23)  = M_L_DQ<23>
  VSS(32)  = GND
  DQ(19)  = M_L_DQ<19>
  VSS(31)  = GND
  DQ(29)  = M_L_DQ<29>
  VSS(30)  = GND
  DQ(25)  = M_L_DQ<25>
  VSS(29)  = GND
  DQS3N  = M_L_DQS_DN<3>
  DQS3P  = M_L_DQS_DP<3>
  VSS(28)  = GND
  DQ(31)  = M_L_DQ<31>
  VSS(27)  = GND
  DQ(27)  = M_L_DQ<27>
  VSS(26)  = GND
  CB(5)  = M_L_ECC<5>
  VSS(25)  = GND
  CB(1)  = M_L_ECC<1>
  VSS(24)  = GND
  DQS8N  = M_L_DQS_DN<8>
  DQS8P  = M_L_DQS_DP<8>
  VSS(23)  = GND
  CB(7)  = M_L_ECC<7>
  VSS(22)  = GND
  CB(3)  = M_L_ECC<3>
  VSS(21)  = GND
  CKE(1)  = M_L_CKE<3>
  VDD(12)  = PVDDQ_KLM
  RFU(0)  = TP_CH_L_DIMM0_RFU_0
  VDD(11)  = PVDDQ_KLM
  BG(1)  = M_L_BG<1>
  ALERT_N  = M_L_ALERT_N
  VDD(10)  = PVDDQ_KLM
  A11  = M_L_MA<11>
  A7  = M_L_MA<7>
  VDD(9)  = PVDDQ_KLM
  A5  = M_L_MA<5>
  A4  = M_L_MA<4>
  VDD(8)  = PVDDQ_KLM
  A2  = M_L_MA<2>
  VDD(7)  = PVDDQ_KLM
  CK1P  = M_L_CLK_DP<3>
  CK1N  = M_L_CLK_DN<3>
  VDD(6)  = PVDDQ_KLM
  VTT(0)  = PVTT_KLM
  PAR  = M_L_PAR
  VDD(5)  = PVDDQ_KLM
  BA(1)  = M_L_BA<1>
  A10  = M_L_MA<10>
  VDD(4)  = PVDDQ_KLM
  RFU(1)  = TP_CH_L_DIMM0_RFU_1
  A14_WE_N  = M_L_MA<14>
  VDD(3)  = PVDDQ_KLM
  SAVE_N_NC  = FM_ADR_COMPLETE_KLM_N
  VDD(2)  = PVDDQ_KLM
  A13  = M_L_MA<13>
  VDD(1)  = PVDDQ_KLM
  A17  = M_L_MA<17>
  C(2)  = M_L_C<2>
  VDD(0)  = PVDDQ_KLM
  S3_N_C(1)  = M_L_CS_N<7>
  SA(2)  = GND
  VSS(20)  = GND
  DQ(37)  = M_L_DQ<37>
  VSS(19)  = GND
  DQ(33)  = M_L_DQ<33>
  VSS(18)  = GND
  DQS4N  = M_L_DQS_DN<4>
  DQS4P  = M_L_DQS_DP<4>
  VSS(17)  = GND
  DQ(39)  = M_L_DQ<39>
  VSS(16)  = GND
  DQ(35)  = M_L_DQ<35>
  VSS(15)  = GND
  DQ(45)  = M_L_DQ<45>
  VSS(14)  = GND
  DQ(41)  = M_L_DQ<41>
  VSS(13)  = GND
  DQS5N  = M_L_DQS_DN<5>
  DQS5P  = M_L_DQS_DP<5>
  VSS(12)  = GND
  DQ(47)  = M_L_DQ<47>
  VSS(11)  = GND
  DQ(43)  = M_L_DQ<43>
  VSS(10)  = GND
  DQ(53)  = M_L_DQ<53>
  VSS(9)  = GND
  DQ(49)  = M_L_DQ<49>
  VSS(8)  = GND
  DQS6N  = M_L_DQS_DN<6>
  DQS6P  = M_L_DQS_DP<6>
  VSS(7)  = GND
  DQ(55)  = M_L_DQ<55>
  VSS(6)  = GND
  DQ(51)  = M_L_DQ<51>
  VSS(5)  = GND
  DQ(61)  = M_L_DQ<61>
  VSS(4)  = GND
  DQ(57)  = M_L_DQ<57>
  VSS(3)  = GND
  DQS7N  = M_L_DQS_DN<7>
  DQS7P  = M_L_DQS_DP<7>
  VSS(2)  = GND
  DQ(63)  = M_L_DQ<63>
  VSS(1)  = GND
  DQ(59)  = M_L_DQ<59>
  VSS(0)  = GND
  VDDSPD  = PVPP_KLM
  SDA  = SMB_DDR_KLM_VPP_SDA
  VPP(1)  = PVPP_KLM
  VPP(0)  = PVPP_KLM
  VPP(2)  = PVPP_KLM

(kicad_pcb
	(version 20260206)
	(generator "pcbnew")
	(generator_version "10.0")
	(general
		(thickness 1.6)
		(legacy_teardrops no)
	)
	(paper "A4")
	(title_block
		(title "Wiwynn_Tioga_Pass_MB.brd")
		(comment 1 "Tioga Pass / footprint 4281 of 4770 (J9L2), pads 1-50 of 291")
	)
	(layers
		(0 "F.Cu" signal "TOP")
		(4 "In1.Cu" signal "L2GND")
		(6 "In2.Cu" signal "L3")
		(8 "In3.Cu" signal "L4GND")
		(10 "In4.Cu" signal "L5")
		(12 "In5.Cu" signal "L6GND")
		(14 "In6.Cu" signal "L7VCC")
		(16 "In7.Cu" signal "L8VCC")
		(18 "In8.Cu" signal "L9GND")
		(20 "In9.Cu" signal "L10")
		(22 "In10.Cu" signal "L11GND")
		(24 "In11.Cu" signal "L12")
		(26 "In12.Cu" signal "L13GND")
		(2 "B.Cu" signal "BOTTOM")
		(9 "F.Adhes" user "F.Adhesive")
		(11 "B.Adhes" user "B.Adhesive")
		(13 "F.Paste" user "Package Geometry/Pastemask Top")
		(15 "B.Paste" user "Package Geometry/Pastemask Bottom")
		(5 "F.SilkS" user "Ref Des/Silkscreen Top")
		(7 "B.SilkS" user "Ref Des/Silkscreen Bottom")
		(1 "F.Mask" user "Board Geometry/Soldermask Top")
		(3 "B.Mask" user "Board Geometry/Soldermask Bottom")
		(17 "Dwgs.User" user "User.Drawings")
		(19 "Cmts.User" user "User.Comments")
		(21 "Eco1.User" user "User.Eco1")
		(23 "Eco2.User" user "User.Eco2")
		(25 "Edge.Cuts" user "Board Geometry/Outline")
		(27 "Margin" user)
		(31 "F.CrtYd" user "Package Geometry/Place Bound Top")
		(29 "B.CrtYd" user "Package Geometry/Place Bound Bottom")
		(35 "F.Fab" user "Ref Des/Assembly Top")
		(33 "B.Fab" user "Ref Des/Assembly Bottom")
	)
	(footprint ""
		(layer "B.Cu")
		(at 29.699458 -142.477236 90)
		(property "Reference" "J9L2"
			(at 2.403348 38.118542 0)
			(unlocked yes)
			(layer "B.SilkS")
			(effects
				(font
					(size 0.7874 0.5842)
					(thickness 0.1524)
				)
				(justify left mirror)
			)
		)
		(property "Value" ""
			(at 0 0 90)
			(layer "B.Fab")
			(effects
				(font
					(size 1.27 1.27)
				)
				(justify mirror)
			)
		)
		(duplicate_pad_numbers_are_jumpers no)
		(pad "" thru_hole circle
			(at -2.29997 -5.649976 270)
			(size 2.8194 2.8194)
			(drill 2.4384)
			(layers "*.Cu" "*.Mask")
			(remove_unused_layers no)
			(clearance 0.127)
			(thermal_gap 0.127)
		)
		(pad "" thru_hole oval
			(at -2.29997 68.90004 270)
			(size 2.8194 1.5748)
			(drill oval 2.4384 1.1938)
			(layers "*.Cu" "*.Mask")
			(remove_unused_layers no)
			(clearance 0.127)
			(thermal_gap 0.127)
		)
		(pad "" thru_hole circle
			(at -2.29997 132.299964 270)
			(size 2.8194 2.8194)
			(drill 2.4384)
			(layers "*.Cu" "*.Mask")
			(remove_unused_layers no)
			(clearance 0.127)
			(thermal_gap 0.127)
		)
		(pad "1" smd rect
			(at 0 0 270)
			(size 1.8034 0.508)
			(layers "B.Cu" "B.Mask" "B.Paste")
			(net "P12V_NVDIMM_KLM")
		)
		(pad "2" smd rect
			(at 0 0.849884 270)
			(size 1.8034 0.508)
			(layers "B.Cu" "B.Mask" "B.Paste")
			(net "GND")
		)
		(pad "3" smd rect
			(at 0 1.700022 270)
			(size 1.8034 0.508)
			(layers "B.Cu" "B.Mask" "B.Paste")
			(net "M_L_DQ<4>")
		)
		(pad "4" smd rect
			(at 0 2.549906 270)
			(size 1.8034 0.508)
			(layers "B.Cu" "B.Mask" "B.Paste")
			(net "GND")
		)
		(pad "5" smd rect
			(at 0 3.400044 270)
			(size 1.8034 0.508)
			(layers "B.Cu" "B.Mask" "B.Paste")
			(net "M_L_DQ<0>")
		)
		(pad "6" smd rect
			(at 0 4.249928 270)
			(size 1.8034 0.508)
			(layers "B.Cu" "B.Mask" "B.Paste")
			(net "GND")
		)
		(pad "7" smd rect
			(at 0 5.100066 270)
			(size 1.8034 0.508)
			(layers "B.Cu" "B.Mask" "B.Paste")
			(net "M_L_DQS_DP<9>")
		)
		(pad "8" smd rect
			(at 0 5.94995 270)
			(size 1.8034 0.508)
			(layers "B.Cu" "B.Mask" "B.Paste")
			(net "M_L_DQS_DN<9>")
		)
		(pad "9" smd rect
			(at 0 6.800088 270)
			(size 1.8034 0.508)
			(layers "B.Cu" "B.Mask" "B.Paste")
			(net "GND")
		)
		(pad "10" smd rect
			(at 0 7.649972 270)
			(size 1.8034 0.508)
			(layers "B.Cu" "B.Mask" "B.Paste")
			(net "M_L_DQ<6>")
		)
		(pad "11" smd rect
			(at 0 8.50011 270)
			(size 1.8034 0.508)
			(layers "B.Cu" "B.Mask" "B.Paste")
			(net "GND")
		)
		(pad "12" smd rect
			(at 0 9.349994 270)
			(size 1.8034 0.508)
			(layers "B.Cu" "B.Mask" "B.Paste")
			(net "M_L_DQ<2>")
		)
		(pad "13" smd rect
			(at 0 10.199878 270)
			(size 1.8034 0.508)
			(layers "B.Cu" "B.Mask" "B.Paste")
			(net "GND")
		)
		(pad "14" smd rect
			(at 0 11.050016 270)
			(size 1.8034 0.508)
			(layers "B.Cu" "B.Mask" "B.Paste")
			(net "M_L_DQ<12>")
		)
		(pad "15" smd rect
			(at 0 11.8999 270)
			(size 1.8034 0.508)
			(layers "B.Cu" "B.Mask" "B.Paste")
			(net "GND")
		)
		(pad "16" smd rect
			(at 0 12.750038 270)
			(size 1.8034 0.508)
			(layers "B.Cu" "B.Mask" "B.Paste")
			(net "M_L_DQ<8>")
		)
		(pad "17" smd rect
			(at 0 13.599922 270)
			(size 1.8034 0.508)
			(layers "B.Cu" "B.Mask" "B.Paste")
			(net "GND")
		)
		(pad "18" smd rect
			(at 0 14.45006 270)
			(size 1.8034 0.508)
			(layers "B.Cu" "B.Mask" "B.Paste")
			(net "M_L_DQS_DP<10>")
		)
		(pad "19" smd rect
			(at 0 15.299944 270)
			(size 1.8034 0.508)
			(layers "B.Cu" "B.Mask" "B.Paste")
			(net "M_L_DQS_DN<10>")
		)
		(pad "20" smd rect
			(at 0 16.150082 270)
			(size 1.8034 0.508)
			(layers "B.Cu" "B.Mask" "B.Paste")
			(net "GND")
		)
		(pad "21" smd rect
			(at 0 16.999966 270)
			(size 1.8034 0.508)
			(layers "B.Cu" "B.Mask" "B.Paste")
			(net "M_L_DQ<14>")
		)
		(pad "22" smd rect
			(at 0 17.850104 270)
			(size 1.8034 0.508)
			(layers "B.Cu" "B.Mask" "B.Paste")
			(net "GND")
		)
		(pad "23" smd rect
			(at 0 18.699988 270)
			(size 1.8034 0.508)
			(layers "B.Cu" "B.Mask" "B.Paste")
			(net "M_L_DQ<10>")
		)
		(pad "24" smd rect
			(at 0 19.550126 270)
			(size 1.8034 0.508)
			(layers "B.Cu" "B.Mask" "B.Paste")
			(net "GND")
		)
		(pad "25" smd rect
			(at 0 20.40001 270)
			(size 1.8034 0.508)
			(layers "B.Cu" "B.Mask" "B.Paste")
			(net "M_L_DQ<20>")
		)
		(pad "26" smd rect
			(at 0 21.249894 270)
			(size 1.8034 0.508)
			(layers "B.Cu" "B.Mask" "B.Paste")
			(net "GND")
		)
		(pad "27" smd rect
			(at 0 22.100032 270)
			(size 1.8034 0.508)
			(layers "B.Cu" "B.Mask" "B.Paste")
			(net "M_L_DQ<16>")
		)
		(pad "28" smd rect
			(at 0 22.949916 270)
			(size 1.8034 0.508)
			(layers "B.Cu" "B.Mask" "B.Paste")
			(net "GND")
		)
		(pad "29" smd rect
			(at 0 23.800054 270)
			(size 1.8034 0.508)
			(layers "B.Cu" "B.Mask" "B.Paste")
			(net "M_L_DQS_DP<11>")
		)
		(pad "30" smd rect
			(at 0 24.649938 270)
			(size 1.8034 0.508)
			(layers "B.Cu" "B.Mask" "B.Paste")
			(net "M_L_DQS_DN<11>")
		)
		(pad "31" smd rect
			(at 0 25.500076 270)
			(size 1.8034 0.508)
			(layers "B.Cu" "B.Mask" "B.Paste")
			(net "GND")
		)
		(pad "32" smd rect
			(at 0 26.34996 270)
			(size 1.8034 0.508)
			(layers "B.Cu" "B.Mask" "B.Paste")
			(net "M_L_DQ<22>")
		)
		(pad "33" smd rect
			(at 0 27.200098 270)
			(size 1.8034 0.508)
			(layers "B.Cu" "B.Mask" "B.Paste")
			(net "GND")
		)
		(pad "34" smd rect
			(at 0 28.049982 270)
			(size 1.8034 0.508)
			(layers "B.Cu" "B.Mask" "B.Paste")
			(net "M_L_DQ<18>")
		)
		(pad "35" smd rect
			(at 0 28.90012 270)
			(size 1.8034 0.508)
			(layers "B.Cu" "B.Mask" "B.Paste")
			(net "GND")
		)
		(pad "36" smd rect
			(at 0 29.750004 270)
			(size 1.8034 0.508)
			(layers "B.Cu" "B.Mask" "B.Paste")
			(net "M_L_DQ<28>")
		)
		(pad "37" smd rect
			(at 0 30.599888 270)
			(size 1.8034 0.508)
			(layers "B.Cu" "B.Mask" "B.Paste")
			(net "GND")
		)
		(pad "38" smd rect
			(at 0 31.450026 270)
			(size 1.8034 0.508)
			(layers "B.Cu" "B.Mask" "B.Paste")
			(net "M_L_DQ<24>")
		)
		(pad "39" smd rect
			(at 0 32.29991 270)
			(size 1.8034 0.508)
			(layers "B.Cu" "B.Mask" "B.Paste")
			(net "GND")
		)
		(pad "40" smd rect
			(at 0 33.150048 270)
			(size 1.8034 0.508)
			(layers "B.Cu" "B.Mask" "B.Paste")
			(net "M_L_DQS_DP<12>")
		)
		(pad "41" smd rect
			(at 0 33.999932 270)
			(size 1.8034 0.508)
			(layers "B.Cu" "B.Mask" "B.Paste")
			(net "M_L_DQS_DN<12>")
		)
		(pad "42" smd rect
			(at 0 34.85007 270)
			(size 1.8034 0.508)
			(layers "B.Cu" "B.Mask" "B.Paste")
			(net "GND")
		)
		(pad "43" smd rect
			(at 0 35.699954 270)
			(size 1.8034 0.508)
			(layers "B.Cu" "B.Mask" "B.Paste")
			(net "M_L_DQ<30>")
		)
		(pad "44" smd rect
			(at 0 36.550092 270)
			(size 1.8034 0.508)
			(layers "B.Cu" "B.Mask" "B.Paste")
			(net "GND")
		)
		(pad "45" smd rect
			(at 0 37.399976 270)
			(size 1.8034 0.508)
			(layers "B.Cu" "B.Mask" "B.Paste")
			(net "M_L_DQ<26>")
		)
		(pad "46" smd rect
			(at 0 38.250114 270)
			(size 1.8034 0.508)
			(layers "B.Cu" "B.Mask" "B.Paste")
			(net "GND")
		)
		(pad "47" smd rect
			(at 0 39.099998 270)
			(size 1.8034 0.508)
			(layers "B.Cu" "B.Mask" "B.Paste")
			(net "M_L_ECC<4>")
		)
	)
)
